(kicad_pcb
	(version 20241229)
	(generator "pcbnew")
	(generator_version "9.0")
	(general
		(thickness 1.294)
		(legacy_teardrops no)
	)
	(paper "A3")
	(title_block
		(title "Kintex 410T devboard")
		(date "2024-04-03")
		(rev "1.1.2")
		(comment 9 "footprints 507-512 of 975")
	)
	(layers
		(0 "F.Cu" mixed)
		(4 "In1.Cu" power)
		(6 "In2.Cu" power)
		(8 "In3.Cu" mixed)
		(10 "In4.Cu" power)
		(12 "In5.Cu" mixed)
		(14 "In6.Cu" power)
		(16 "In7.Cu" mixed)
		(18 "In8.Cu" power)
		(2 "B.Cu" mixed)
		(9 "F.Adhes" user "F.Adhesive")
		(11 "B.Adhes" user "B.Adhesive")
		(13 "F.Paste" user)
		(15 "B.Paste" user)
		(5 "F.SilkS" user "F.Silkscreen")
		(7 "B.SilkS" user "B.Silkscreen")
		(1 "F.Mask" user)
		(3 "B.Mask" user)
		(17 "Dwgs.User" user "User.Drawings")
		(19 "Cmts.User" user "User.Comments")
		(21 "Eco1.User" user "User.Eco1")
		(23 "Eco2.User" user "User.Eco2")
		(25 "Edge.Cuts" user)
		(27 "Margin" user)
		(31 "F.CrtYd" user "F.Courtyard")
		(29 "B.CrtYd" user "B.Courtyard")
		(35 "F.Fab" user)
		(33 "B.Fab" user)
	)
	(footprint "antmicro-footprints:C_0402_1005Metric"
		(layer "B.Cu")
		(at 258.201 166.8 90)
		(descr "Capacitor SMD 0402")
		(tags "capacitor SMD 0402")
		(property "Reference" "C275"
			(at 0.375 1.049 225)
			(layer "B.SilkS")
			(effects
				(font
					(size 0.7 0.7)
					(thickness 0.15)
				)
				(justify right bottom mirror)
			)
		)
		(property "Value" "C_10p_0402"
			(at 0 -1.4 90)
			(layer "B.Fab")
			(effects
				(font
					(size 0.7 0.7)
					(thickness 0.15)
				)
				(justify right bottom mirror)
			)
		)
		(property "Description" "SMD Multilayer Ceramic Capacitor, 10 pF, 50 V, 0402 [1005 Metric], ± 2%, C0G / NP0, GCM"
			(at 0 0 90)
			(layer "F.Fab")
			(hide yes)
			(effects
				(font
					(size 1.27 1.27)
					(thickness 0.15)
				)
			)
		)
		(property "Author" "Antmicro"
			(at 425.001 -91.401 0)
			(layer "B.Fab")
			(hide yes)
			(effects
				(font
					(size 1 1)
					(thickness 0.15)
				)
				(justify mirror)
			)
		)
		(property "Dielectric" "C0G"
			(at 425.001 -91.401 0)
			(layer "B.Fab")
			(hide yes)
			(effects
				(font
					(size 1 1)
					(thickness 0.15)
				)
				(justify mirror)
			)
		)
		(property "License" "Apache-2.0"
			(at 425.001 -91.401 0)
			(layer "B.Fab")
			(hide yes)
			(effects
				(font
					(size 1 1)
					(thickness 0.15)
				)
				(justify mirror)
			)
		)
		(property "MPN" "GCM1555C1H100GA16D"
			(at 425.001 -91.401 0)
			(layer "B.Fab")
			(hide yes)
			(effects
				(font
					(size 1 1)
					(thickness 0.15)
				)
				(justify mirror)
			)
		)
		(property "Manufacturer" "Murata"
			(at 425.001 -91.401 0)
			(layer "B.Fab")
			(hide yes)
			(effects
				(font
					(size 1 1)
					(thickness 0.15)
				)
				(justify mirror)
			)
		)
		(property "Val" "10p"
			(at 425.001 -91.401 0)
			(layer "B.Fab")
			(hide yes)
			(effects
				(font
					(size 1 1)
					(thickness 0.15)
				)
				(justify mirror)
			)
		)
		(property "Voltage" "50V"
			(at 425.001 -91.401 0)
			(layer "B.Fab")
			(hide yes)
			(effects
				(font
					(size 1 1)
					(thickness 0.15)
				)
				(justify mirror)
			)
		)
		(sheetname "HDMI + Ethernet")
		(sheetfile "hdmi-ethernet.kicad_sch")
		(attr smd)
		(fp_rect
			(start -0.925 0.47)
			(end 0.925 -0.47)
			(stroke
				(width 0.05)
				(type default)
			)
			(fill no)
			(layer "B.CrtYd")
		)
		(fp_line
			(start 0.504 -0.248)
			(end -0.494 -0.248)
			(stroke
				(width 0.15)
				(type solid)
			)
			(layer "B.Fab")
		)
		(fp_line
			(start -0.494 -0.248)
			(end -0.494 0.25)
			(stroke
				(width 0.15)
				(type solid)
			)
			(layer "B.Fab")
		)
		(fp_line
			(start 0.504 0.25)
			(end 0.504 -0.248)
			(stroke
				(width 0.15)
				(type solid)
			)
			(layer "B.Fab")
		)
		(fp_line
			(start -0.494 0.25)
			(end 0.504 0.25)
			(stroke
				(width 0.15)
				(type solid)
			)
			(layer "B.Fab")
		)
		(pad "1" smd roundrect
			(at -0.48 0 90)
			(size 0.59 0.64)
			(layers "B.Cu" "B.Mask" "B.Paste")
			(roundrect_rratio 0.25)
			(net 1 "GND")
			(pintype "passive")
		)
		(pad "2" smd roundrect
			(at 0.48 0 90)
			(size 0.59 0.64)
			(layers "B.Cu" "B.Mask" "B.Paste")
			(roundrect_rratio 0.25)
			(net 725 "/HDMI + Ethernet/ETH1_N")
			(pintype "passive")
		)
	)
	(footprint "antmicro-footprints:C_0402_1005Metric"
		(layer "B.Cu")
		(at 216.09 128.51 135)
		(descr "Capacitor SMD 0402")
		(tags "capacitor SMD 0402")
		(property "Reference" "C42"
			(at -1.078338 -1.240972 315)
			(unlocked yes)
			(layer "B.SilkS")
			(effects
				(font
					(size 0.7 0.7)
					(thickness 0.15)
				)
				(justify left bottom mirror)
			)
		)
		(property "Value" "C_100n_0402"
			(at 0 -1.169 315)
			(layer "B.Fab")
			(effects
				(font
					(size 0.7 0.7)
					(thickness 0.15)
				)
				(justify left bottom mirror)
			)
		)
		(property "Description" "SMD Multilayer Ceramic Capacitor, 0.1 µF, 50 V, 0402 [1005 Metric], ± 10%, X5R, GRM Series"
			(at 0 0 135)
			(layer "F.Fab")
			(hide yes)
			(effects
				(font
					(size 1.27 1.27)
					(thickness 0.15)
				)
			)
		)
		(property "Author" "Antmicro"
			(at 459.758997 66.581588 0)
			(layer "B.Fab")
			(hide yes)
			(effects
				(font
					(size 1 1)
					(thickness 0.15)
				)
				(justify mirror)
			)
		)
		(property "Dielectric" "X5R"
			(at 459.758997 66.581588 0)
			(layer "B.Fab")
			(hide yes)
			(effects
				(font
					(size 1 1)
					(thickness 0.15)
				)
				(justify mirror)
			)
		)
		(property "License" "Apache-2.0"
			(at 459.758997 66.581588 0)
			(layer "B.Fab")
			(hide yes)
			(effects
				(font
					(size 1 1)
					(thickness 0.15)
				)
				(justify mirror)
			)
		)
		(property "MPN" "GRM155R61H104KE14D"
			(at 459.758997 66.581588 0)
			(layer "B.Fab")
			(hide yes)
			(effects
				(font
					(size 1 1)
					(thickness 0.15)
				)
				(justify mirror)
			)
		)
		(property "Manufacturer" "Murata"
			(at 459.758997 66.581588 0)
			(layer "B.Fab")
			(hide yes)
			(effects
				(font
					(size 1 1)
					(thickness 0.15)
				)
				(justify mirror)
			)
		)
		(property "Val" "100n"
			(at 459.758997 66.581588 0)
			(layer "B.Fab")
			(hide yes)
			(effects
				(font
					(size 1 1)
					(thickness 0.15)
				)
				(justify mirror)
			)
		)
		(property "Voltage" "50V"
			(at 459.758997 66.581588 0)
			(layer "B.Fab")
			(hide yes)
			(effects
				(font
					(size 1 1)
					(thickness 0.15)
				)
				(justify mirror)
			)
		)
		(sheetname "FPGA Bank 14 & 15")
		(sheetfile "fpga-bank-14-15.kicad_sch")
		(attr smd)
		(fp_poly
			(pts
				(xy -0.925 0.47) (xy 0.925 0.47) (xy 0.925 -0.47) (xy -0.925 -0.47)
			)
			(stroke
				(width 0.05)
				(type default)
			)
			(fill no)
			(layer "B.CrtYd")
		)
		(fp_line
			(start 0.504 -0.248)
			(end -0.494 -0.248)
			(stroke
				(width 0.15)
				(type solid)
			)
			(layer "B.Fab")
		)
		(fp_line
			(start 0.504 0.25)
			(end 0.504 -0.248)
			(stroke
				(width 0.15)
				(type solid)
			)
			(layer "B.Fab")
		)
		(fp_line
			(start -0.494 -0.248)
			(end -0.494 0.25)
			(stroke
				(width 0.15)
				(type solid)
			)
			(layer "B.Fab")
		)
		(fp_line
			(start -0.494 0.25)
			(end 0.504 0.25)
			(stroke
				(width 0.15)
				(type solid)
			)
			(layer "B.Fab")
		)
		(pad "1" smd roundrect
			(at -0.48 0 135)
			(size 0.59 0.64)
			(layers "B.Cu" "B.Mask" "B.Paste")
			(roundrect_rratio 0.25)
			(net 1 "GND")
			(pintype "passive")
		)
		(pad "2" smd roundrect
			(at 0.48 0 135)
			(size 0.59 0.64)
			(layers "B.Cu" "B.Mask" "B.Paste")
			(roundrect_rratio 0.25)
			(net 24 "+3V3")
			(pintype "passive")
		)
	)
	(footprint "antmicro-footprints:R_0402_1005Metric"
		(layer "B.Cu")
		(at 203.2 92.7 -90)
		(descr "Resistor SMD 0402")
		(tags "resistor SMD 0402")
		(property "Reference" "R214"
			(at -0.9 -2.4 90)
			(layer "B.SilkS")
			(effects
				(font
					(size 0.7 0.7)
					(thickness 0.15)
				)
				(justify left bottom mirror)
			)
		)
		(property "Value" "R_2k2_0402"
			(at 0 -1.4 90)
			(layer "B.Fab")
			(effects
				(font
					(size 0.7 0.7)
					(thickness 0.15)
				)
				(justify left bottom mirror)
			)
		)
		(property "Description" "SMD Chip Resistor, 2.2 kohm, ± 1%, 62.5 mW, 0402 [1005 Metric], Thick Film, General Purpose"
			(at 0 0 270)
			(layer "F.Fab")
			(hide yes)
			(effects
				(font
					(size 1.27 1.27)
					(thickness 0.15)
				)
			)
		)
		(property "Author" "Antmicro"
			(at 110.5 295.9 0)
			(layer "B.Fab")
			(hide yes)
			(effects
				(font
					(size 1 1)
					(thickness 0.15)
				)
				(justify mirror)
			)
		)
		(property "DNP" "DNP"
			(at 110.5 295.9 0)
			(layer "B.Fab")
			(hide yes)
			(effects
				(font
					(size 1 1)
					(thickness 0.15)
				)
				(justify mirror)
			)
		)
		(property "License" "Apache-2.0"
			(at 110.5 295.9 0)
			(layer "B.Fab")
			(hide yes)
			(effects
				(font
					(size 1 1)
					(thickness 0.15)
				)
				(justify mirror)
			)
		)
		(property "MPN" "CR0402-FX-2201GLF"
			(at 110.5 295.9 0)
			(layer "B.Fab")
			(hide yes)
			(effects
				(font
					(size 1 1)
					(thickness 0.15)
				)
				(justify mirror)
			)
		)
		(property "Manufacturer" "Bourns"
			(at 110.5 295.9 0)
			(layer "B.Fab")
			(hide yes)
			(effects
				(font
					(size 1 1)
					(thickness 0.15)
				)
				(justify mirror)
			)
		)
		(property "Tolerance" "1%"
			(at 110.5 295.9 0)
			(layer "B.Fab")
			(hide yes)
			(effects
				(font
					(size 1 1)
					(thickness 0.15)
				)
				(justify mirror)
			)
		)
		(property "Val" "2k2"
			(at 110.5 295.9 0)
			(layer "B.Fab")
			(hide yes)
			(effects
				(font
					(size 1 1)
					(thickness 0.15)
				)
				(justify mirror)
			)
		)
		(property "dnp" ""
			(at 110.5 295.9 0)
			(layer "B.Fab")
			(hide yes)
			(effects
				(font
					(size 1 1)
					(thickness 0.15)
				)
				(justify mirror)
			)
		)
		(property "exclude_from_bom" ""
			(at 110.5 295.9 0)
			(layer "B.Fab")
			(hide yes)
			(effects
				(font
					(size 1 1)
					(thickness 0.15)
				)
				(justify mirror)
			)
		)
		(sheetname "HDMI + Ethernet")
		(sheetfile "hdmi-ethernet.kicad_sch")
		(attr smd exclude_from_bom)
		(fp_rect
			(start -0.925 0.47)
			(end 0.925 -0.47)
			(stroke
				(width 0.05)
				(type default)
			)
			(fill no)
			(layer "B.CrtYd")
		)
		(fp_rect
			(start -0.5 0.25)
			(end 0.5 -0.25)
			(stroke
				(width 0.15)
				(type solid)
			)
			(fill no)
			(layer "B.Fab")
		)
		(pad "1" smd roundrect
			(at -0.48 0 270)
			(size 0.59 0.64)
			(layers "B.Cu" "B.Mask" "B.Paste")
			(roundrect_rratio 0.25)
			(net 850 "/HDMI + Ethernet/GBE_LED_SPD-")
			(pintype "passive")
		)
		(pad "2" smd roundrect
			(at 0.48 0 270)
			(size 0.59 0.64)
			(layers "B.Cu" "B.Mask" "B.Paste")
			(roundrect_rratio 0.25)
			(net 1 "GND")
			(pintype "passive")
		)
	)
	(footprint "antmicro-footprints:C_0402_1005Metric"
		(layer "B.Cu")
		(at 187.950001 132.775001 180)
		(descr "Capacitor SMD 0402")
		(tags "capacitor SMD 0402")
		(property "Reference" "C155"
			(at -0.949999 -1.199999 0)
			(layer "B.SilkS")
			(effects
				(font
					(size 0.7 0.7)
					(thickness 0.15)
				)
				(justify left bottom mirror)
			)
		)
		(property "Value" "C_100n_0402"
			(at 0 -1.169 0)
			(layer "B.Fab")
			(effects
				(font
					(size 0.7 0.7)
					(thickness 0.15)
				)
				(justify left bottom mirror)
			)
		)
		(property "Description" "SMD Multilayer Ceramic Capacitor, 0.1 µF, 50 V, 0402 [1005 Metric], ± 10%, X5R, GRM Series"
			(at 0 0 180)
			(layer "F.Fab")
			(hide yes)
			(effects
				(font
					(size 1.27 1.27)
					(thickness 0.15)
				)
			)
		)
		(property "Author" "Antmicro"
			(at 375.900002 265.550002 0)
			(layer "B.Fab")
			(hide yes)
			(effects
				(font
					(size 1 1)
					(thickness 0.15)
				)
				(justify mirror)
			)
		)
		(property "Dielectric" "X5R"
			(at 375.900002 265.550002 0)
			(layer "B.Fab")
			(hide yes)
			(effects
				(font
					(size 1 1)
					(thickness 0.15)
				)
				(justify mirror)
			)
		)
		(property "License" "Apache-2.0"
			(at 375.900002 265.550002 0)
			(layer "B.Fab")
			(hide yes)
			(effects
				(font
					(size 1 1)
					(thickness 0.15)
				)
				(justify mirror)
			)
		)
		(property "MPN" "GRM155R61H104KE14D"
			(at 375.900002 265.550002 0)
			(layer "B.Fab")
			(hide yes)
			(effects
				(font
					(size 1 1)
					(thickness 0.15)
				)
				(justify mirror)
			)
		)
		(property "Manufacturer" "Murata"
			(at 375.900002 265.550002 0)
			(layer "B.Fab")
			(hide yes)
			(effects
				(font
					(size 1 1)
					(thickness 0.15)
				)
				(justify mirror)
			)
		)
		(property "Val" "100n"
			(at 375.900002 265.550002 0)
			(layer "B.Fab")
			(hide yes)
			(effects
				(font
					(size 1 1)
					(thickness 0.15)
				)
				(justify mirror)
			)
		)
		(property "Voltage" "50V"
			(at 375.900002 265.550002 0)
			(layer "B.Fab")
			(hide yes)
			(effects
				(font
					(size 1 1)
					(thickness 0.15)
				)
				(justify mirror)
			)
		)
		(sheetname "FPGA supply")
		(sheetfile "fpga-supply.kicad_sch")
		(attr smd)
		(fp_rect
			(start -0.925 0.47)
			(end 0.925 -0.47)
			(stroke
				(width 0.05)
				(type default)
			)
			(fill no)
			(layer "B.CrtYd")
		)
		(fp_line
			(start 0.504 0.25)
			(end 0.504 -0.248)
			(stroke
				(width 0.15)
				(type solid)
			)
			(layer "B.Fab")
		)
		(fp_line
			(start 0.504 -0.248)
			(end -0.494 -0.248)
			(stroke
				(width 0.15)
				(type solid)
			)
			(layer "B.Fab")
		)
		(fp_line
			(start -0.494 0.25)
			(end 0.504 0.25)
			(stroke
				(width 0.15)
				(type solid)
			)
			(layer "B.Fab")
		)
		(fp_line
			(start -0.494 -0.248)
			(end -0.494 0.25)
			(stroke
				(width 0.15)
				(type solid)
			)
			(layer "B.Fab")
		)
		(pad "1" smd roundrect
			(at -0.48 0 180)
			(size 0.59 0.64)
			(layers "B.Cu" "B.Mask" "B.Paste")
			(roundrect_rratio 0.25)
			(net 1 "GND")
			(pintype "passive")
		)
		(pad "2" smd roundrect
			(at 0.48 0 180)
			(size 0.59 0.64)
			(layers "B.Cu" "B.Mask" "B.Paste")
			(roundrect_rratio 0.25)
			(net 8 "+1V2_MGTAVTT")
			(pintype "passive")
		)
	)
	(footprint "antmicro-footprints:R_0402_1005Metric"
		(layer "B.Cu")
		(at 251.301 141.25 -90)
		(descr "Resistor SMD 0402")
		(tags "resistor SMD 0402")
		(property "Reference" "R86"
			(at 0.75 -0.399 90)
			(layer "B.SilkS")
			(effects
				(font
					(size 0.7 0.7)
					(thickness 0.15)
				)
				(justify left bottom mirror)
			)
		)
		(property "Value" "R_10k_0402"
			(at 0 -1.4 90)
			(layer "B.Fab")
			(effects
				(font
					(size 0.7 0.7)
					(thickness 0.15)
				)
				(justify left bottom mirror)
			)
		)
		(property "Description" "SMD Chip Resistor, 10 kohm, ± 1%, 62.5 mW, 0402 [1005 Metric], Thick Film, General Purpose"
			(at 0 0 270)
			(layer "F.Fab")
			(hide yes)
			(effects
				(font
					(size 1.27 1.27)
					(thickness 0.15)
				)
			)
		)
		(property "Author" "Antmicro"
			(at 110.051 392.551 0)
			(layer "B.Fab")
			(hide yes)
			(effects
				(font
					(size 1 1)
					(thickness 0.15)
				)
				(justify mirror)
			)
		)
		(property "License" "Apache-2.0"
			(at 110.051 392.551 0)
			(layer "B.Fab")
			(hide yes)
			(effects
				(font
					(size 1 1)
					(thickness 0.15)
				)
				(justify mirror)
			)
		)
		(property "MPN" "CR0402-FX-1002GLF"
			(at 110.051 392.551 0)
			(layer "B.Fab")
			(hide yes)
			(effects
				(font
					(size 1 1)
					(thickness 0.15)
				)
				(justify mirror)
			)
		)
		(property "Manufacturer" "Bourns"
			(at 110.051 392.551 0)
			(layer "B.Fab")
			(hide yes)
			(effects
				(font
					(size 1 1)
					(thickness 0.15)
				)
				(justify mirror)
			)
		)
		(property "Tolerance" "1%"
			(at 110.051 392.551 0)
			(layer "B.Fab")
			(hide yes)
			(effects
				(font
					(size 1 1)
					(thickness 0.15)
				)
				(justify mirror)
			)
		)
		(property "Val" "10k"
			(at 110.051 392.551 0)
			(layer "B.Fab")
			(hide yes)
			(effects
				(font
					(size 1 1)
					(thickness 0.15)
				)
				(justify mirror)
			)
		)
		(sheetname "SPI Flash + SD Card")
		(sheetfile "spi-flash.kicad_sch")
		(attr smd)
		(fp_rect
			(start -0.925 0.47)
			(end 0.925 -0.47)
			(stroke
				(width 0.05)
				(type default)
			)
			(fill no)
			(layer "B.CrtYd")
		)
		(fp_rect
			(start -0.5 0.25)
			(end 0.5 -0.25)
			(stroke
				(width 0.15)
				(type solid)
			)
			(fill no)
			(layer "B.Fab")
		)
		(pad "1" smd roundrect
			(at -0.48 0 270)
			(size 0.59 0.64)
			(layers "B.Cu" "B.Mask" "B.Paste")
			(roundrect_rratio 0.25)
			(net 390 "/FPGA Bank 33 & 34/SD_CARD.DAT2")
			(pintype "passive")
		)
		(pad "2" smd roundrect
			(at 0.48 0 270)
			(size 0.59 0.64)
			(layers "B.Cu" "B.Mask" "B.Paste")
			(roundrect_rratio 0.25)
			(net 24 "+3V3")
			(pintype "passive")
		)
	)
	(footprint "antmicro-footprints:C_0402_1005Metric"
		(layer "B.Cu")
		(at 160.45 188.6)
		(descr "Capacitor SMD 0402")
		(tags "capacitor SMD 0402")
		(property "Reference" "C336"
			(at -3.575 0.4 0)
			(layer "B.SilkS")
			(effects
				(font
					(size 0.7 0.7)
					(thickness 0.15)
				)
				(justify right bottom mirror)
			)
		)
		(property "Value" "C_100n_0402"
			(at 0 -1.4 0)
			(layer "B.Fab")
			(effects
				(font
					(size 0.7 0.7)
					(thickness 0.15)
				)
				(justify right bottom mirror)
			)
		)
		(property "Description" "SMD Multilayer Ceramic Capacitor, 0.1 µF, 50 V, 0402 [1005 Metric], ± 10%, X5R, GRM Series"
			(at 0 0 0)
			(layer "F.Fab")
			(hide yes)
			(effects
				(font
					(size 1.27 1.27)
					(thickness 0.15)
				)
			)
		)
		(property "Author" "Antmicro"
			(at 0 0 0)
			(layer "B.Fab")
			(hide yes)
			(effects
				(font
					(size 1 1)
					(thickness 0.15)
				)
				(justify mirror)
			)
		)
		(property "Dielectric" "X5R"
			(at 0 0 0)
			(layer "B.Fab")
			(hide yes)
			(effects
				(font
					(size 1 1)
					(thickness 0.15)
				)
				(justify mirror)
			)
		)
		(property "License" "Apache-2.0"
			(at 0 0 0)
			(layer "B.Fab")
			(hide yes)
			(effects
				(font
					(size 1 1)
					(thickness 0.15)
				)
				(justify mirror)
			)
		)
		(property "MPN" "GRM155R61H104KE14D"
			(at 0 0 0)
			(layer "B.Fab")
			(hide yes)
			(effects
				(font
					(size 1 1)
					(thickness 0.15)
				)
				(justify mirror)
			)
		)
		(property "Manufacturer" "Murata"
			(at 0 0 0)
			(layer "B.Fab")
			(hide yes)
			(effects
				(font
					(size 1 1)
					(thickness 0.15)
				)
				(justify mirror)
			)
		)
		(property "Val" "100n"
			(at 0 0 0)
			(layer "B.Fab")
			(hide yes)
			(effects
				(font
					(size 1 1)
					(thickness 0.15)
				)
				(justify mirror)
			)
		)
		(property "Voltage" "50V"
			(at 0 0 0)
			(layer "B.Fab")
			(hide yes)
			(effects
				(font
					(size 1 1)
					(thickness 0.15)
				)
				(justify mirror)
			)
		)
		(sheetname "DC-DC Converters")
		(sheetfile "dc-dc.kicad_sch")
		(attr smd)
		(fp_rect
			(start -0.925 0.47)
			(end 0.925 -0.47)
			(stroke
				(width 0.05)
				(type default)
			)
			(fill no)
			(layer "B.CrtYd")
		)
		(fp_line
			(start -0.494 -0.248)
			(end -0.494 0.25)
			(stroke
				(width 0.15)
				(type solid)
			)
			(layer "B.Fab")
		)
		(fp_line
			(start -0.494 0.25)
			(end 0.504 0.25)
			(stroke
				(width 0.15)
				(type solid)
			)
			(layer "B.Fab")
		)
		(fp_line
			(start 0.504 -0.248)
			(end -0.494 -0.248)
			(stroke
				(width 0.15)
				(type solid)
			)
			(layer "B.Fab")
		)
		(fp_line
			(start 0.504 0.25)
			(end 0.504 -0.248)
			(stroke
				(width 0.15)
				(type solid)
			)
			(layer "B.Fab")
		)
		(pad "1" smd roundrect
			(at -0.48 0)
			(size 0.59 0.64)
			(layers "B.Cu" "B.Mask" "B.Paste")
			(roundrect_rratio 0.25)
			(net 1 "GND")
			(pintype "passive")
		)
		(pad "2" smd roundrect
			(at 0.48 0)
			(size 0.59 0.64)
			(layers "B.Cu" "B.Mask" "B.Paste")
			(roundrect_rratio 0.25)
			(net 37 "+3V3_AON")
			(pintype "passive")
		)
	)
)
